(kicad_pcb
	(version 20260206)
	(generator "pcbnew")
	(generator_version "10.0")
	(general
		(thickness 1.6)
		(legacy_teardrops no)
	)
	(paper "A4")
	(title_block
		(title "01162023_DA0F0TEBIF0_F0T_Expander_BD_F_brd_V02_OCP.brd")
		(comment 1 "Grand Teton / footprints 3863-3869 of 9728")
	)
	(layers
		(0 "F.Cu" signal "TOP")
		(4 "In1.Cu" signal "GND")
		(6 "In2.Cu" signal "VCC")
		(8 "In3.Cu" signal "VCC1")
		(10 "In4.Cu" signal "GND1")
		(12 "In5.Cu" signal "IN1")
		(14 "In6.Cu" signal "GND2")
		(16 "In7.Cu" signal "IN2")
		(18 "In8.Cu" signal "GND3")
		(20 "In9.Cu" signal "IN3")
		(22 "In10.Cu" signal "GND4")
		(24 "In11.Cu" signal "IN4")
		(26 "In12.Cu" signal "GND5")
		(28 "In13.Cu" signal "IN5")
		(30 "In14.Cu" signal "GND6")
		(32 "In15.Cu" signal "IN6")
		(34 "In16.Cu" signal "GND7")
		(2 "B.Cu" signal "BOTTOM")
		(9 "F.Adhes" user "F.Adhesive")
		(11 "B.Adhes" user "B.Adhesive")
		(13 "F.Paste" user "Package Geometry/Pastemask Top")
		(15 "B.Paste" user "Package Geometry/Pastemask Bottom")
		(5 "F.SilkS" user "Ref Des/Silkscreen Top")
		(7 "B.SilkS" user "Ref Des/Silkscreen Bottom")
		(1 "F.Mask" user "Board Geometry/Soldermask Top")
		(3 "B.Mask" user "Board Geometry/Soldermask Bottom")
		(17 "Dwgs.User" user "User.Drawings")
		(19 "Cmts.User" user "User.Comments")
		(21 "Eco1.User" user "User.Eco1")
		(23 "Eco2.User" user "User.Eco2")
		(25 "Edge.Cuts" user "Board Geometry/Outline")
		(27 "Margin" user)
		(31 "F.CrtYd" user "Package Geometry/Place Bound Top")
		(29 "B.CrtYd" user "Package Geometry/Place Bound Bottom")
		(35 "F.Fab" user "Ref Des/Assembly Top")
		(33 "B.Fab" user "Ref Des/Assembly Bottom")
	)
	(footprint ""
		(layer "F.Cu")
		(at 252.634496 -30.94609 180)
		(property "Reference" "C491"
			(at 0 0 180)
			(layer "F.SilkS")
			(hide yes)
			(effects
				(font
					(size 1.27 1.27)
				)
			)
		)
		(property "Value" ""
			(at 0 0 180)
			(layer "F.Fab")
			(effects
				(font
					(size 1.27 1.27)
				)
			)
		)
		(duplicate_pad_numbers_are_jumpers no)
		(fp_line
			(start 0.299974 0.150114)
			(end -0.299974 0.150114)
			(stroke
				(width 0.1)
				(type default)
			)
			(layer "F.Fab")
		)
		(fp_line
			(start 0.299974 -0.150114)
			(end 0.299974 0.150114)
			(stroke
				(width 0.1)
				(type default)
			)
			(layer "F.Fab")
		)
		(fp_line
			(start -0.299974 0.150114)
			(end -0.299974 -0.150114)
			(stroke
				(width 0.1)
				(type default)
			)
			(layer "F.Fab")
		)
		(fp_line
			(start -0.299974 -0.150114)
			(end 0.299974 -0.150114)
			(stroke
				(width 0.1)
				(type default)
			)
			(layer "F.Fab")
		)
		(pad "1" smd rect
			(at -0.2667 0 180)
			(size 0.3048 0.381)
			(layers "F.Cu" "F.Mask" "F.Paste")
			(net "P5E_PEX2_STN2_TX_DP<45>")
		)
		(pad "2" smd rect
			(at 0.2667 0 180)
			(size 0.3048 0.381)
			(layers "F.Cu" "F.Mask" "F.Paste")
			(net "P5E_PEX2_STN2_TX_C_DP<45>")
		)
	)
	(footprint ""
		(layer "F.Cu")
		(at 87.73795 -291.102034 180)
		(property "Reference" "R6389"
			(at 0 0 180)
			(layer "F.SilkS")
			(hide yes)
			(effects
				(font
					(size 1.27 1.27)
				)
			)
		)
		(property "Value" ""
			(at 0 0 180)
			(layer "F.Fab")
			(effects
				(font
					(size 1.27 1.27)
				)
			)
		)
		(duplicate_pad_numbers_are_jumpers no)
		(fp_line
			(start 0.7874 0.4064)
			(end -0.7874 0.4064)
			(stroke
				(width 0.1524)
				(type default)
			)
			(layer "F.SilkS")
		)
		(fp_line
			(start 0.7874 -0.4064)
			(end 0.7874 0.4064)
			(stroke
				(width 0.1524)
				(type default)
			)
			(layer "F.SilkS")
		)
		(fp_line
			(start -0.7874 0.4064)
			(end -0.7874 -0.4064)
			(stroke
				(width 0.1524)
				(type default)
			)
			(layer "F.SilkS")
		)
		(fp_line
			(start -0.7874 -0.4064)
			(end 0.7874 -0.4064)
			(stroke
				(width 0.1524)
				(type default)
			)
			(layer "F.SilkS")
		)
		(fp_line
			(start 0.67945 0.3048)
			(end 0.120396 0.3048)
			(stroke
				(width 0.1)
				(type default)
			)
			(layer "F.Fab")
		)
		(fp_line
			(start 0.67945 -0.3048)
			(end 0.67945 0.3048)
			(stroke
				(width 0.1)
				(type default)
			)
			(layer "F.Fab")
		)
		(fp_line
			(start 0.12065 -0.2794)
			(end 0.12065 -0.3048)
			(stroke
				(width 0.1)
				(type default)
			)
			(layer "F.Fab")
		)
		(fp_line
			(start 0.12065 -0.3048)
			(end 0.67945 -0.3048)
			(stroke
				(width 0.1)
				(type default)
			)
			(layer "F.Fab")
		)
		(fp_line
			(start 0.120396 0.3048)
			(end 0.120396 0.2794)
			(stroke
				(width 0.1)
				(type default)
			)
			(layer "F.Fab")
		)
		(fp_line
			(start 0.120396 0.2794)
			(end -0.12065 0.2794)
			(stroke
				(width 0.1)
				(type default)
			)
			(layer "F.Fab")
		)
		(fp_line
			(start -0.12065 0.3048)
			(end -0.67945 0.3048)
			(stroke
				(width 0.1)
				(type default)
			)
			(layer "F.Fab")
		)
		(fp_line
			(start -0.12065 0.2794)
			(end -0.12065 0.3048)
			(stroke
				(width 0.1)
				(type default)
			)
			(layer "F.Fab")
		)
		(fp_line
			(start -0.12065 -0.2794)
			(end 0.12065 -0.2794)
			(stroke
				(width 0.1)
				(type default)
			)
			(layer "F.Fab")
		)
		(fp_line
			(start -0.12065 -0.305054)
			(end -0.12065 -0.2794)
			(stroke
				(width 0.1)
				(type default)
			)
			(layer "F.Fab")
		)
		(fp_line
			(start -0.67945 0.3048)
			(end -0.67945 -0.305054)
			(stroke
				(width 0.1)
				(type default)
			)
			(layer "F.Fab")
		)
		(fp_line
			(start -0.67945 -0.305054)
			(end -0.12065 -0.305054)
			(stroke
				(width 0.1)
				(type default)
			)
			(layer "F.Fab")
		)
		(pad "1" smd circle
			(at -0.40005 0 180)
			(size 0 0)
			(layers "F.Cu" "F.Mask" "F.Paste")
			(net "GND")
		)
		(pad "2" smd circle
			(at 0.40005 0 180)
			(size 0 0)
			(layers "F.Cu" "F.Mask" "F.Paste")
			(net "RST_PEX0_PERST_R_N")
		)
	)
	(footprint ""
		(layer "F.Cu")
		(at 213.754716 -22.867366 90)
		(property "Reference" "C3923"
			(at 0 0 90)
			(layer "F.SilkS")
			(hide yes)
			(effects
				(font
					(size 1.27 1.27)
				)
			)
		)
		(property "Value" ""
			(at 0 0 90)
			(layer "F.Fab")
			(effects
				(font
					(size 1.27 1.27)
				)
			)
		)
		(duplicate_pad_numbers_are_jumpers no)
		(fp_line
			(start 0.7874 -0.4064)
			(end 0.7874 0.4064)
			(stroke
				(width 0.1524)
				(type default)
			)
			(layer "F.SilkS")
		)
		(fp_line
			(start -0.7874 -0.4064)
			(end 0.7874 -0.4064)
			(stroke
				(width 0.1524)
				(type default)
			)
			(layer "F.SilkS")
		)
		(fp_line
			(start 0.7874 0.4064)
			(end -0.7874 0.4064)
			(stroke
				(width 0.1524)
				(type default)
			)
			(layer "F.SilkS")
		)
		(fp_line
			(start -0.7874 0.4064)
			(end -0.7874 -0.4064)
			(stroke
				(width 0.1524)
				(type default)
			)
			(layer "F.SilkS")
		)
		(fp_line
			(start -0.12065 -0.305054)
			(end -0.12065 -0.2794)
			(stroke
				(width 0.1)
				(type default)
			)
			(layer "F.Fab")
		)
		(fp_line
			(start -0.67945 -0.305054)
			(end -0.12065 -0.305054)
			(stroke
				(width 0.1)
				(type default)
			)
			(layer "F.Fab")
		)
		(fp_line
			(start 0.67945 -0.3048)
			(end 0.67945 0.3048)
			(stroke
				(width 0.1)
				(type default)
			)
			(layer "F.Fab")
		)
		(fp_line
			(start 0.12065 -0.3048)
			(end 0.67945 -0.3048)
			(stroke
				(width 0.1)
				(type default)
			)
			(layer "F.Fab")
		)
		(fp_line
			(start 0.12065 -0.2794)
			(end 0.12065 -0.3048)
			(stroke
				(width 0.1)
				(type default)
			)
			(layer "F.Fab")
		)
		(fp_line
			(start -0.12065 -0.2794)
			(end 0.12065 -0.2794)
			(stroke
				(width 0.1)
				(type default)
			)
			(layer "F.Fab")
		)
		(fp_line
			(start 0.120396 0.2794)
			(end -0.12065 0.2794)
			(stroke
				(width 0.1)
				(type default)
			)
			(layer "F.Fab")
		)
		(fp_line
			(start -0.12065 0.2794)
			(end -0.12065 0.3048)
			(stroke
				(width 0.1)
				(type default)
			)
			(layer "F.Fab")
		)
		(fp_line
			(start 0.67945 0.3048)
			(end 0.120396 0.3048)
			(stroke
				(width 0.1)
				(type default)
			)
			(layer "F.Fab")
		)
		(fp_line
			(start 0.120396 0.3048)
			(end 0.120396 0.2794)
			(stroke
				(width 0.1)
				(type default)
			)
			(layer "F.Fab")
		)
		(fp_line
			(start -0.12065 0.3048)
			(end -0.67945 0.3048)
			(stroke
				(width 0.1)
				(type default)
			)
			(layer "F.Fab")
		)
		(fp_line
			(start -0.67945 0.3048)
			(end -0.67945 -0.305054)
			(stroke
				(width 0.1)
				(type default)
			)
			(layer "F.Fab")
		)
		(pad "1" smd circle
			(at -0.40005 0 90)
			(size 0 0)
			(layers "F.Cu" "F.Mask" "F.Paste")
			(net "P12V_SSD7")
		)
		(pad "2" smd circle
			(at 0.40005 0 90)
			(size 0 0)
			(layers "F.Cu" "F.Mask" "F.Paste")
			(net "GND")
		)
	)
	(footprint ""
		(layer "F.Cu")
		(at 121.13514 -97.177606)
		(property "Reference" "R1551"
			(at 0 0 0)
			(layer "F.SilkS")
			(hide yes)
			(effects
				(font
					(size 1.27 1.27)
				)
			)
		)
		(property "Value" ""
			(at 0 0 0)
			(layer "F.Fab")
			(effects
				(font
					(size 1.27 1.27)
				)
			)
		)
		(duplicate_pad_numbers_are_jumpers no)
		(fp_line
			(start -0.7874 -0.4064)
			(end 0.7874 -0.4064)
			(stroke
				(width 0.1524)
				(type default)
			)
			(layer "F.SilkS")
		)
		(fp_line
			(start -0.7874 0.4064)
			(end -0.7874 -0.4064)
			(stroke
				(width 0.1524)
				(type default)
			)
			(layer "F.SilkS")
		)
		(fp_line
			(start 0.7874 -0.4064)
			(end 0.7874 0.4064)
			(stroke
				(width 0.1524)
				(type default)
			)
			(layer "F.SilkS")
		)
		(fp_line
			(start 0.7874 0.4064)
			(end -0.7874 0.4064)
			(stroke
				(width 0.1524)
				(type default)
			)
			(layer "F.SilkS")
		)
		(fp_line
			(start -0.67945 -0.305054)
			(end -0.12065 -0.305054)
			(stroke
				(width 0.1)
				(type default)
			)
			(layer "F.Fab")
		)
		(fp_line
			(start -0.67945 0.3048)
			(end -0.67945 -0.305054)
			(stroke
				(width 0.1)
				(type default)
			)
			(layer "F.Fab")
		)
		(fp_line
			(start -0.12065 -0.305054)
			(end -0.12065 -0.2794)
			(stroke
				(width 0.1)
				(type default)
			)
			(layer "F.Fab")
		)
		(fp_line
			(start -0.12065 -0.2794)
			(end 0.12065 -0.2794)
			(stroke
				(width 0.1)
				(type default)
			)
			(layer "F.Fab")
		)
		(fp_line
			(start -0.12065 0.2794)
			(end -0.12065 0.3048)
			(stroke
				(width 0.1)
				(type default)
			)
			(layer "F.Fab")
		)
		(fp_line
			(start -0.12065 0.3048)
			(end -0.67945 0.3048)
			(stroke
				(width 0.1)
				(type default)
			)
			(layer "F.Fab")
		)
		(fp_line
			(start 0.120396 0.2794)
			(end -0.12065 0.2794)
			(stroke
				(width 0.1)
				(type default)
			)
			(layer "F.Fab")
		)
		(fp_line
			(start 0.120396 0.3048)
			(end 0.120396 0.2794)
			(stroke
				(width 0.1)
				(type default)
			)
			(layer "F.Fab")
		)
		(fp_line
			(start 0.12065 -0.3048)
			(end 0.67945 -0.3048)
			(stroke
				(width 0.1)
				(type default)
			)
			(layer "F.Fab")
		)
		(fp_line
			(start 0.12065 -0.2794)
			(end 0.12065 -0.3048)
			(stroke
				(width 0.1)
				(type default)
			)
			(layer "F.Fab")
		)
		(fp_line
			(start 0.67945 -0.3048)
			(end 0.67945 0.3048)
			(stroke
				(width 0.1)
				(type default)
			)
			(layer "F.Fab")
		)
		(fp_line
			(start 0.67945 0.3048)
			(end 0.120396 0.3048)
			(stroke
				(width 0.1)
				(type default)
			)
			(layer "F.Fab")
		)
		(pad "1" smd circle
			(at -0.40005 0)
			(size 0 0)
			(layers "F.Cu" "F.Mask" "F.Paste")
			(net "P3V3_AUX")
		)
		(pad "2" smd circle
			(at 0.40005 0)
			(size 0 0)
			(layers "F.Cu" "F.Mask" "F.Paste")
			(net "SMB_BIC_I2C9_MUX0_SSD0_R_SDA")
		)
	)
	(footprint ""
		(layer "F.Cu")
		(at 228.953568 -306.386992 -90)
		(property "Reference" "PC241"
			(at 0 0 270)
			(layer "F.SilkS")
			(hide yes)
			(effects
				(font
					(size 1.27 1.27)
				)
			)
		)
		(property "Value" ""
			(at 0 0 270)
			(layer "F.Fab")
			(effects
				(font
					(size 1.27 1.27)
				)
			)
		)
		(duplicate_pad_numbers_are_jumpers no)
		(fp_line
			(start -0.7874 0.4064)
			(end -0.7874 -0.4064)
			(stroke
				(width 0.1524)
				(type default)
			)
			(layer "F.SilkS")
		)
		(fp_line
			(start 0.7874 0.4064)
			(end -0.7874 0.4064)
			(stroke
				(width 0.1524)
				(type default)
			)
			(layer "F.SilkS")
		)
		(fp_line
			(start -0.7874 -0.4064)
			(end 0.7874 -0.4064)
			(stroke
				(width 0.1524)
				(type default)
			)
			(layer "F.SilkS")
		)
		(fp_line
			(start 0.7874 -0.4064)
			(end 0.7874 0.4064)
			(stroke
				(width 0.1524)
				(type default)
			)
			(layer "F.SilkS")
		)
		(fp_line
			(start -0.67945 0.3048)
			(end -0.67945 -0.305054)
			(stroke
				(width 0.1)
				(type default)
			)
			(layer "F.Fab")
		)
		(fp_line
			(start -0.12065 0.3048)
			(end -0.67945 0.3048)
			(stroke
				(width 0.1)
				(type default)
			)
			(layer "F.Fab")
		)
		(fp_line
			(start 0.120396 0.3048)
			(end 0.120396 0.2794)
			(stroke
				(width 0.1)
				(type default)
			)
			(layer "F.Fab")
		)
		(fp_line
			(start 0.67945 0.3048)
			(end 0.120396 0.3048)
			(stroke
				(width 0.1)
				(type default)
			)
			(layer "F.Fab")
		)
		(fp_line
			(start -0.12065 0.2794)
			(end -0.12065 0.3048)
			(stroke
				(width 0.1)
				(type default)
			)
			(layer "F.Fab")
		)
		(fp_line
			(start 0.120396 0.2794)
			(end -0.12065 0.2794)
			(stroke
				(width 0.1)
				(type default)
			)
			(layer "F.Fab")
		)
		(fp_line
			(start -0.12065 -0.2794)
			(end 0.12065 -0.2794)
			(stroke
				(width 0.1)
				(type default)
			)
			(layer "F.Fab")
		)
		(fp_line
			(start 0.12065 -0.2794)
			(end 0.12065 -0.3048)
			(stroke
				(width 0.1)
				(type default)
			)
			(layer "F.Fab")
		)
		(fp_line
			(start 0.12065 -0.3048)
			(end 0.67945 -0.3048)
			(stroke
				(width 0.1)
				(type default)
			)
			(layer "F.Fab")
		)
		(fp_line
			(start 0.67945 -0.3048)
			(end 0.67945 0.3048)
			(stroke
				(width 0.1)
				(type default)
			)
			(layer "F.Fab")
		)
		(fp_line
			(start -0.67945 -0.305054)
			(end -0.12065 -0.305054)
			(stroke
				(width 0.1)
				(type default)
			)
			(layer "F.Fab")
		)
		(fp_line
			(start -0.12065 -0.305054)
			(end -0.12065 -0.2794)
			(stroke
				(width 0.1)
				(type default)
			)
			(layer "F.Fab")
		)
		(pad "1" smd circle
			(at -0.40005 0 270)
			(size 0 0)
			(layers "F.Cu" "F.Mask" "F.Paste")
			(net "P1V25_PEX1_REF")
		)
		(pad "2" smd circle
			(at 0.40005 0 270)
			(size 0 0)
			(layers "F.Cu" "F.Mask" "F.Paste")
			(net "GND")
		)
	)
	(footprint ""
		(layer "F.Cu")
		(at 457.555092 -375.090182)
		(property "Reference" "R6684"
			(at 0 0 0)
			(layer "F.SilkS")
			(hide yes)
			(effects
				(font
					(size 1.27 1.27)
				)
			)
		)
		(property "Value" ""
			(at 0 0 0)
			(layer "F.Fab")
			(effects
				(font
					(size 1.27 1.27)
				)
			)
		)
		(duplicate_pad_numbers_are_jumpers no)
		(fp_line
			(start -0.7874 -0.4064)
			(end 0.7874 -0.4064)
			(stroke
				(width 0.1524)
				(type default)
			)
			(layer "F.SilkS")
		)
		(fp_line
			(start -0.7874 0.4064)
			(end -0.7874 -0.4064)
			(stroke
				(width 0.1524)
				(type default)
			)
			(layer "F.SilkS")
		)
		(fp_line
			(start 0.7874 -0.4064)
			(end 0.7874 0.4064)
			(stroke
				(width 0.1524)
				(type default)
			)
			(layer "F.SilkS")
		)
		(fp_line
			(start 0.7874 0.4064)
			(end -0.7874 0.4064)
			(stroke
				(width 0.1524)
				(type default)
			)
			(layer "F.SilkS")
		)
		(fp_line
			(start -0.67945 -0.305054)
			(end -0.12065 -0.305054)
			(stroke
				(width 0.1)
				(type default)
			)
			(layer "F.Fab")
		)
		(fp_line
			(start -0.67945 0.3048)
			(end -0.67945 -0.305054)
			(stroke
				(width 0.1)
				(type default)
			)
			(layer "F.Fab")
		)
		(fp_line
			(start -0.12065 -0.305054)
			(end -0.12065 -0.2794)
			(stroke
				(width 0.1)
				(type default)
			)
			(layer "F.Fab")
		)
		(fp_line
			(start -0.12065 -0.2794)
			(end 0.12065 -0.2794)
			(stroke
				(width 0.1)
				(type default)
			)
			(layer "F.Fab")
		)
		(fp_line
			(start -0.12065 0.2794)
			(end -0.12065 0.3048)
			(stroke
				(width 0.1)
				(type default)
			)
			(layer "F.Fab")
		)
		(fp_line
			(start -0.12065 0.3048)
			(end -0.67945 0.3048)
			(stroke
				(width 0.1)
				(type default)
			)
			(layer "F.Fab")
		)
		(fp_line
			(start 0.120396 0.2794)
			(end -0.12065 0.2794)
			(stroke
				(width 0.1)
				(type default)
			)
			(layer "F.Fab")
		)
		(fp_line
			(start 0.120396 0.3048)
			(end 0.120396 0.2794)
			(stroke
				(width 0.1)
				(type default)
			)
			(layer "F.Fab")
		)
		(fp_line
			(start 0.12065 -0.3048)
			(end 0.67945 -0.3048)
			(stroke
				(width 0.1)
				(type default)
			)
			(layer "F.Fab")
		)
		(fp_line
			(start 0.12065 -0.2794)
			(end 0.12065 -0.3048)
			(stroke
				(width 0.1)
				(type default)
			)
			(layer "F.Fab")
		)
		(fp_line
			(start 0.67945 -0.3048)
			(end 0.67945 0.3048)
			(stroke
				(width 0.1)
				(type default)
			)
			(layer "F.Fab")
		)
		(fp_line
			(start 0.67945 0.3048)
			(end 0.120396 0.3048)
			(stroke
				(width 0.1)
				(type default)
			)
			(layer "F.Fab")
		)
		(pad "1" smd circle
			(at -0.40005 0)
			(size 0 0)
			(layers "F.Cu" "F.Mask" "F.Paste")
			(net "GPU_3V3IO_RSVD3_N")
		)
		(pad "2" smd circle
			(at 0.40005 0)
			(size 0 0)
			(layers "F.Cu" "F.Mask" "F.Paste")
			(net "P3V3_AUX")
		)
	)
	(footprint ""
		(layer "F.Cu")
		(at 282.681934 -37.025072)
		(property "Reference" "R5693"
			(at 0 0 0)
			(layer "F.SilkS")
			(hide yes)
			(effects
				(font
					(size 1.27 1.27)
				)
			)
		)
		(property "Value" ""
			(at 0 0 0)
			(layer "F.Fab")
			(effects
				(font
					(size 1.27 1.27)
				)
			)
		)
		(duplicate_pad_numbers_are_jumpers no)
		(fp_line
			(start -0.7874 -0.4064)
			(end 0.7874 -0.4064)
			(stroke
				(width 0.1524)
				(type default)
			)
			(layer "F.SilkS")
		)
		(fp_line
			(start -0.7874 0.4064)
			(end -0.7874 -0.4064)
			(stroke
				(width 0.1524)
				(type default)
			)
			(layer "F.SilkS")
		)
		(fp_line
			(start 0.7874 -0.4064)
			(end 0.7874 0.4064)
			(stroke
				(width 0.1524)
				(type default)
			)
			(layer "F.SilkS")
		)
		(fp_line
			(start 0.7874 0.4064)
			(end -0.7874 0.4064)
			(stroke
				(width 0.1524)
				(type default)
			)
			(layer "F.SilkS")
		)
		(fp_line
			(start -0.67945 -0.305054)
			(end -0.12065 -0.305054)
			(stroke
				(width 0.1)
				(type default)
			)
			(layer "F.Fab")
		)
		(fp_line
			(start -0.67945 0.3048)
			(end -0.67945 -0.305054)
			(stroke
				(width 0.1)
				(type default)
			)
			(layer "F.Fab")
		)
		(fp_line
			(start -0.12065 -0.305054)
			(end -0.12065 -0.2794)
			(stroke
				(width 0.1)
				(type default)
			)
			(layer "F.Fab")
		)
		(fp_line
			(start -0.12065 -0.2794)
			(end 0.12065 -0.2794)
			(stroke
				(width 0.1)
				(type default)
			)
			(layer "F.Fab")
		)
		(fp_line
			(start -0.12065 0.2794)
			(end -0.12065 0.3048)
			(stroke
				(width 0.1)
				(type default)
			)
			(layer "F.Fab")
		)
		(fp_line
			(start -0.12065 0.3048)
			(end -0.67945 0.3048)
			(stroke
				(width 0.1)
				(type default)
			)
			(layer "F.Fab")
		)
		(fp_line
			(start 0.120396 0.2794)
			(end -0.12065 0.2794)
			(stroke
				(width 0.1)
				(type default)
			)
			(layer "F.Fab")
		)
		(fp_line
			(start 0.120396 0.3048)
			(end 0.120396 0.2794)
			(stroke
				(width 0.1)
				(type default)
			)
			(layer "F.Fab")
		)
		(fp_line
			(start 0.12065 -0.3048)
			(end 0.67945 -0.3048)
			(stroke
				(width 0.1)
				(type default)
			)
			(layer "F.Fab")
		)
		(fp_line
			(start 0.12065 -0.2794)
			(end 0.12065 -0.3048)
			(stroke
				(width 0.1)
				(type default)
			)
			(layer "F.Fab")
		)
		(fp_line
			(start 0.67945 -0.3048)
			(end 0.67945 0.3048)
			(stroke
				(width 0.1)
				(type default)
			)
			(layer "F.Fab")
		)
		(fp_line
			(start 0.67945 0.3048)
			(end 0.120396 0.3048)
			(stroke
				(width 0.1)
				(type default)
			)
			(layer "F.Fab")
		)
		(pad "1" smd circle
			(at -0.40005 0)
			(size 0 0)
			(layers "F.Cu" "F.Mask" "F.Paste")
			(net "RST_SMB_SSD_R_N")
		)
		(pad "2" smd circle
			(at 0.40005 0)
			(size 0 0)
			(layers "F.Cu" "F.Mask" "F.Paste")
			(net "RST_SMB_SSD10_N")
		)
	)
)
